# T6G (Grand Teton) — schematic netlist excerpt (pin names and nets, part order shuffled) for the footprints in the layout excerpt that follows; sources: Cadence DE-HDL packaged netlist, KiCad conversion of 04192023_DAF0TMB3IC0_F0TG_MB_C_brd_V02_OCP.brd

R190  Q_RES  0 5% CHIP  pkg 0402LF  page 82 : A = FM_CPU1_BMC_RST_N ; B = FM_CPU1_BMC_RST_R_N
C44  Q_CAP_DIFFBUS  DIFF BUS_0.22UF 6.3V 20% X6S  pkg C0201  page 65 : \1\ = P5E_CPU0_G3_TX_C_DP<8> ; \2\ = P5E_CPU0_G3_TX_DP<8>
PC577  Q_CAP  0.1UF 25V 10% X7R  pkg 0402  page 190 : A = SW_P3V3_AUX_FLT ; B = GND

(kicad_pcb
	(version 20260206)
	(generator "pcbnew")
	(generator_version "10.0")
	(general
		(thickness 1.6)
		(legacy_teardrops no)
	)
	(paper "A4")
	(title_block
		(title "04192023_DAF0TMB3IC0_F0TG_MB_C_brd_V02_OCP.brd")
		(comment 1 "Grand Teton / footprints 3819-3821 of 8354")
	)
	(layers
		(0 "F.Cu" signal "TOP")
		(4 "In1.Cu" signal "GND")
		(6 "In2.Cu" signal "IN1")
		(8 "In3.Cu" signal "GND1")
		(10 "In4.Cu" signal "IN2")
		(12 "In5.Cu" signal "GND2")
		(14 "In6.Cu" signal "IN3")
		(16 "In7.Cu" signal "GND3")
		(18 "In8.Cu" signal "VCC")
		(20 "In9.Cu" signal "VCC1")
		(22 "In10.Cu" signal "GND4")
		(24 "In11.Cu" signal "IN4")
		(26 "In12.Cu" signal "GND5")
		(28 "In13.Cu" signal "IN5")
		(30 "In14.Cu" signal "GND6")
		(32 "In15.Cu" signal "IN6")
		(34 "In16.Cu" signal "GND7")
		(2 "B.Cu" signal "BOTTOM")
		(9 "F.Adhes" user "F.Adhesive")
		(11 "B.Adhes" user "B.Adhesive")
		(13 "F.Paste" user "Package Geometry/Pastemask Top")
		(15 "B.Paste" user "Package Geometry/Pastemask Bottom")
		(5 "F.SilkS" user "Ref Des/Silkscreen Top")
		(7 "B.SilkS" user "Ref Des/Silkscreen Bottom")
		(1 "F.Mask" user "Board Geometry/Soldermask Top")
		(3 "B.Mask" user "Board Geometry/Soldermask Bottom")
		(17 "Dwgs.User" user "User.Drawings")
		(19 "Cmts.User" user "User.Comments")
		(21 "Eco1.User" user "User.Eco1")
		(23 "Eco2.User" user "User.Eco2")
		(25 "Edge.Cuts" user "Board Geometry/Outline")
		(27 "Margin" user)
		(31 "F.CrtYd" user "Package Geometry/Place Bound Top")
		(29 "B.CrtYd" user "Package Geometry/Place Bound Bottom")
		(35 "F.Fab" user "Ref Des/Assembly Top")
		(33 "B.Fab" user "Ref Des/Assembly Bottom")
	)
	(footprint ""
		(layer "F.Cu")
		(at 410.479748 -17.624298 90)
		(property "Reference" "C44"
			(at 0 0 90)
			(layer "F.SilkS")
			(hide yes)
			(effects
				(font
					(size 1.27 1.27)
				)
			)
		)
		(property "Value" ""
			(at 0 0 90)
			(layer "F.Fab")
			(effects
				(font
					(size 1.27 1.27)
				)
			)
		)
		(duplicate_pad_numbers_are_jumpers no)
		(fp_line
			(start 0.299974 -0.150114)
			(end 0.299974 0.150114)
			(stroke
				(width 0.1)
				(type default)
			)
			(layer "F.Fab")
		)
		(fp_line
			(start -0.299974 -0.150114)
			(end 0.299974 -0.150114)
			(stroke
				(width 0.1)
				(type default)
			)
			(layer "F.Fab")
		)
		(fp_line
			(start 0.299974 0.150114)
			(end -0.299974 0.150114)
			(stroke
				(width 0.1)
				(type default)
			)
			(layer "F.Fab")
		)
		(fp_line
			(start -0.299974 0.150114)
			(end -0.299974 -0.150114)
			(stroke
				(width 0.1)
				(type default)
			)
			(layer "F.Fab")
		)
		(pad "1" smd rect
			(at -0.2667 0 90)
			(size 0.3048 0.381)
			(layers "F.Cu" "F.Mask" "F.Paste")
			(net "P5E_CPU0_G3_TX_C_DP<8>")
		)
		(pad "2" smd rect
			(at 0.2667 0 90)
			(size 0.3048 0.381)
			(layers "F.Cu" "F.Mask" "F.Paste")
			(net "P5E_CPU0_G3_TX_DP<8>")
		)
	)
	(footprint ""
		(layer "F.Cu")
		(at 452.995792 -53.075078 90)
		(property "Reference" "PC577"
			(at 0 0 90)
			(layer "F.SilkS")
			(hide yes)
			(effects
				(font
					(size 1.27 1.27)
				)
			)
		)
		(property "Value" ""
			(at 0 0 90)
			(layer "F.Fab")
			(effects
				(font
					(size 1.27 1.27)
				)
			)
		)
		(duplicate_pad_numbers_are_jumpers no)
		(fp_line
			(start 0.7874 -0.4064)
			(end 0.7874 0.4064)
			(stroke
				(width 0.1524)
				(type default)
			)
			(layer "F.SilkS")
		)
		(fp_line
			(start -0.7874 -0.4064)
			(end 0.7874 -0.4064)
			(stroke
				(width 0.1524)
				(type default)
			)
			(layer "F.SilkS")
		)
		(fp_line
			(start 0.7874 0.4064)
			(end -0.7874 0.4064)
			(stroke
				(width 0.1524)
				(type default)
			)
			(layer "F.SilkS")
		)
		(fp_line
			(start -0.7874 0.4064)
			(end -0.7874 -0.4064)
			(stroke
				(width 0.1524)
				(type default)
			)
			(layer "F.SilkS")
		)
		(fp_line
			(start -0.12065 -0.305054)
			(end -0.12065 -0.2794)
			(stroke
				(width 0.1)
				(type default)
			)
			(layer "F.Fab")
		)
		(fp_line
			(start -0.67945 -0.305054)
			(end -0.12065 -0.305054)
			(stroke
				(width 0.1)
				(type default)
			)
			(layer "F.Fab")
		)
		(fp_line
			(start 0.67945 -0.3048)
			(end 0.67945 0.3048)
			(stroke
				(width 0.1)
				(type default)
			)
			(layer "F.Fab")
		)
		(fp_line
			(start 0.12065 -0.3048)
			(end 0.67945 -0.3048)
			(stroke
				(width 0.1)
				(type default)
			)
			(layer "F.Fab")
		)
		(fp_line
			(start 0.12065 -0.2794)
			(end 0.12065 -0.3048)
			(stroke
				(width 0.1)
				(type default)
			)
			(layer "F.Fab")
		)
		(fp_line
			(start -0.12065 -0.2794)
			(end 0.12065 -0.2794)
			(stroke
				(width 0.1)
				(type default)
			)
			(layer "F.Fab")
		)
		(fp_line
			(start 0.120396 0.2794)
			(end -0.12065 0.2794)
			(stroke
				(width 0.1)
				(type default)
			)
			(layer "F.Fab")
		)
		(fp_line
			(start -0.12065 0.2794)
			(end -0.12065 0.3048)
			(stroke
				(width 0.1)
				(type default)
			)
			(layer "F.Fab")
		)
		(fp_line
			(start 0.67945 0.3048)
			(end 0.120396 0.3048)
			(stroke
				(width 0.1)
				(type default)
			)
			(layer "F.Fab")
		)
		(fp_line
			(start 0.120396 0.3048)
			(end 0.120396 0.2794)
			(stroke
				(width 0.1)
				(type default)
			)
			(layer "F.Fab")
		)
		(fp_line
			(start -0.12065 0.3048)
			(end -0.67945 0.3048)
			(stroke
				(width 0.1)
				(type default)
			)
			(layer "F.Fab")
		)
		(fp_line
			(start -0.67945 0.3048)
			(end -0.67945 -0.305054)
			(stroke
				(width 0.1)
				(type default)
			)
			(layer "F.Fab")
		)
		(pad "1" smd circle
			(at -0.40005 0 90)
			(size 0 0)
			(layers "F.Cu" "F.Mask" "F.Paste")
			(net "SW_P3V3_AUX_FLT")
		)
		(pad "2" smd circle
			(at 0.40005 0 90)
			(size 0 0)
			(layers "F.Cu" "F.Mask" "F.Paste")
			(net "GND")
		)
	)
	(footprint ""
		(layer "F.Cu")
		(at 179.705 -100.294948 90)
		(property "Reference" "R190"
			(at 0 0 90)
			(layer "F.SilkS")
			(hide yes)
			(effects
				(font
					(size 1.27 1.27)
				)
			)
		)
		(property "Value" ""
			(at 0 0 90)
			(layer "F.Fab")
			(effects
				(font
					(size 1.27 1.27)
				)
			)
		)
		(duplicate_pad_numbers_are_jumpers no)
		(fp_line
			(start 0.7874 -0.4064)
			(end 0.7874 0.4064)
			(stroke
				(width 0.1524)
				(type default)
			)
			(layer "F.SilkS")
		)
		(fp_line
			(start -0.7874 -0.4064)
			(end 0.7874 -0.4064)
			(stroke
				(width 0.1524)
				(type default)
			)
			(layer "F.SilkS")
		)
		(fp_line
			(start 0.7874 0.4064)
			(end -0.7874 0.4064)
			(stroke
				(width 0.1524)
				(type default)
			)
			(layer "F.SilkS")
		)
		(fp_line
			(start -0.7874 0.4064)
			(end -0.7874 -0.4064)
			(stroke
				(width 0.1524)
				(type default)
			)
			(layer "F.SilkS")
		)
		(fp_line
			(start -0.12065 -0.305054)
			(end -0.12065 -0.2794)
			(stroke
				(width 0.1)
				(type default)
			)
			(layer "F.Fab")
		)
		(fp_line
			(start -0.67945 -0.305054)
			(end -0.12065 -0.305054)
			(stroke
				(width 0.1)
				(type default)
			)
			(layer "F.Fab")
		)
		(fp_line
			(start 0.67945 -0.3048)
			(end 0.67945 0.3048)
			(stroke
				(width 0.1)
				(type default)
			)
			(layer "F.Fab")
		)
		(fp_line
			(start 0.12065 -0.3048)
			(end 0.67945 -0.3048)
			(stroke
				(width 0.1)
				(type default)
			)
			(layer "F.Fab")
		)
		(fp_line
			(start 0.12065 -0.2794)
			(end 0.12065 -0.3048)
			(stroke
				(width 0.1)
				(type default)
			)
			(layer "F.Fab")
		)
		(fp_line
			(start -0.12065 -0.2794)
			(end 0.12065 -0.2794)
			(stroke
				(width 0.1)
				(type default)
			)
			(layer "F.Fab")
		)
		(fp_line
			(start 0.120396 0.2794)
			(end -0.12065 0.2794)
			(stroke
				(width 0.1)
				(type default)
			)
			(layer "F.Fab")
		)
		(fp_line
			(start -0.12065 0.2794)
			(end -0.12065 0.3048)
			(stroke
				(width 0.1)
				(type default)
			)
			(layer "F.Fab")
		)
		(fp_line
			(start 0.67945 0.3048)
			(end 0.120396 0.3048)
			(stroke
				(width 0.1)
				(type default)
			)
			(layer "F.Fab")
		)
		(fp_line
			(start 0.120396 0.3048)
			(end 0.120396 0.2794)
			(stroke
				(width 0.1)
				(type default)
			)
			(layer "F.Fab")
		)
		(fp_line
			(start -0.12065 0.3048)
			(end -0.67945 0.3048)
			(stroke
				(width 0.1)
				(type default)
			)
			(layer "F.Fab")
		)
		(fp_line
			(start -0.67945 0.3048)
			(end -0.67945 -0.305054)
			(stroke
				(width 0.1)
				(type default)
			)
			(layer "F.Fab")
		)
		(pad "1" smd circle
			(at -0.40005 0 90)
			(size 0 0)
			(layers "F.Cu" "F.Mask" "F.Paste")
			(net "FM_CPU1_BMC_RST_N")
		)
		(pad "2" smd circle
			(at 0.40005 0 90)
			(size 0 0)
			(layers "F.Cu" "F.Mask" "F.Paste")
			(net "FM_CPU1_BMC_RST_R_N")
		)
	)
)
